(kicad_pcb
	(version 20260206)
	(generator "pcbnew")
	(generator_version "10.0")
	(general
		(thickness 1.6)
		(legacy_teardrops no)
	)
	(paper "A4")
	(title_block
		(title "pdpb — Lightning_PDPB_BRD.brd")
		(comment 1 "Lightning (Wiwynn / Facebook NVMe JBOF) / footprints 995-1000 of 1140")
	)
	(layers
		(0 "F.Cu" signal "TOP")
		(4 "In1.Cu" signal "L2GND")
		(6 "In2.Cu" signal "L3")
		(8 "In3.Cu" signal "L4VCC")
		(10 "In4.Cu" signal "L5VCC")
		(12 "In5.Cu" signal "L6")
		(14 "In6.Cu" signal "L7GND")
		(2 "B.Cu" signal "BOTTOM")
		(9 "F.Adhes" user "F.Adhesive")
		(11 "B.Adhes" user "B.Adhesive")
		(13 "F.Paste" user "Package Geometry/Pastemask Top")
		(15 "B.Paste" user "Package Geometry/Pastemask Bottom")
		(5 "F.SilkS" user "Ref Des/Silkscreen Top")
		(7 "B.SilkS" user "Ref Des/Silkscreen Bottom")
		(1 "F.Mask" user "Board Geometry/Soldermask Top")
		(3 "B.Mask" user "Board Geometry/Soldermask Bottom")
		(17 "Dwgs.User" user "User.Drawings")
		(19 "Cmts.User" user "User.Comments")
		(21 "Eco1.User" user "User.Eco1")
		(23 "Eco2.User" user "User.Eco2")
		(25 "Edge.Cuts" user "Board Geometry/Outline")
		(27 "Margin" user)
		(31 "F.CrtYd" user "Package Geometry/Place Bound Top")
		(29 "B.CrtYd" user "Package Geometry/Place Bound Bottom")
		(35 "F.Fab" user "Ref Des/Assembly Top")
		(33 "B.Fab" user "Ref Des/Assembly Bottom")
	)
	(footprint ""
		(layer "F.Cu")
		(at 225.1075 -450.4055 90)
		(property "Reference" "R9782"
			(at 0 0 90)
			(layer "F.SilkS")
			(hide yes)
			(effects
				(font
					(size 1.27 1.27)
				)
			)
		)
		(property "Value" "0R2J-2-GP"
			(at 0.064008 -3.993896 90)
			(unlocked yes)
			(layer "F.Fab")
			(hide yes)
			(effects
				(font
					(size 1.016 1.016)
					(thickness 0.1524)
				)
			)
		)
		(property "Device Type" "R402H16"
			(at 0.064008 -5.517896 90)
			(unlocked yes)
			(layer "F.Fab")
			(hide yes)
			(effects
				(font
					(size 1.016 1.016)
					(thickness 0.1524)
				)
			)
		)
		(duplicate_pad_numbers_are_jumpers no)
		(fp_line
			(start 0.508 -0.9398)
			(end -0.508 -0.9398)
			(stroke
				(width 0.1524)
				(type default)
			)
			(layer "F.SilkS")
		)
		(fp_line
			(start -0.508 -0.9398)
			(end -0.508 0.9398)
			(stroke
				(width 0.1524)
				(type default)
			)
			(layer "F.SilkS")
		)
		(fp_rect
			(start -0.508 0.9398)
			(end 0.508 -0.9398)
			(stroke
				(width 0)
				(type default)
			)
			(fill no)
			(layer "F.CrtYd")
		)
		(fp_rect
			(start -0.508 0.9398)
			(end 0.508 -0.9398)
			(stroke
				(width 0)
				(type default)
			)
			(fill no)
			(layer "F.Fab")
		)
		(pad "1" smd custom
			(at 0 -0.4445 90)
			(size 0.1397 0.1397)
			(layers "F.Cu" "F.Mask" "F.Paste")
			(net "ATTN_LED_DR0_R")
			(options
				(clearance outline)
				(anchor circle)
			)
			(primitives
				(gr_poly
					(pts
						(arc
							(start -0.1778 -0.2794)
							(mid -0.249642 -0.249642)
							(end -0.2794 -0.1778)
						)
						(arc
							(start -0.2794 0.1778)
							(mid -0.249642 0.249642)
							(end -0.1778 0.2794)
						)
						(arc
							(start 0.1778 0.2794)
							(mid 0.249642 0.249642)
							(end 0.2794 0.1778)
						)
						(arc
							(start 0.2794 -0.1778)
							(mid 0.249642 -0.249642)
							(end 0.1778 -0.2794)
						)
					)
					(width 0)
					(fill yes)
				)
			)
		)
		(pad "2" smd custom
			(at 0 0.4445 90)
			(size 0.1397 0.1397)
			(layers "F.Cu" "F.Mask" "F.Paste")
			(net "ATTN_LED_DR0_N")
			(options
				(clearance outline)
				(anchor circle)
			)
			(primitives
				(gr_poly
					(pts
						(arc
							(start -0.1778 -0.2794)
							(mid -0.249642 -0.249642)
							(end -0.2794 -0.1778)
						)
						(arc
							(start -0.2794 0.1778)
							(mid -0.249642 0.249642)
							(end -0.1778 0.2794)
						)
						(arc
							(start 0.1778 0.2794)
							(mid 0.249642 0.249642)
							(end 0.2794 0.1778)
						)
						(arc
							(start 0.2794 -0.1778)
							(mid 0.249642 -0.249642)
							(end 0.1778 -0.2794)
						)
					)
					(width 0)
					(fill yes)
				)
			)
		)
	)
	(footprint ""
		(layer "F.Cu")
		(at 107.442 -436.499 -90)
		(property "Reference" "R9591"
			(at 0 0 270)
			(layer "F.SilkS")
			(hide yes)
			(effects
				(font
					(size 1.27 1.27)
				)
			)
		)
		(property "Value" "10R2F-L-GP"
			(at 0.064008 -3.993896 270)
			(unlocked yes)
			(layer "F.Fab")
			(hide yes)
			(effects
				(font
					(size 1.016 1.016)
					(thickness 0.1524)
				)
			)
		)
		(property "Device Type" "R402H14"
			(at 0.064008 -5.517896 270)
			(unlocked yes)
			(layer "F.Fab")
			(hide yes)
			(effects
				(font
					(size 1.016 1.016)
					(thickness 0.1524)
				)
			)
		)
		(duplicate_pad_numbers_are_jumpers no)
		(fp_line
			(start -0.508 -0.9398)
			(end -0.508 0.9398)
			(stroke
				(width 0.1524)
				(type default)
			)
			(layer "F.SilkS")
		)
		(fp_line
			(start 0.508 -0.9398)
			(end -0.508 -0.9398)
			(stroke
				(width 0.1524)
				(type default)
			)
			(layer "F.SilkS")
		)
		(fp_rect
			(start -0.508 0.9398)
			(end 0.508 -0.9398)
			(stroke
				(width 0)
				(type default)
			)
			(fill no)
			(layer "F.CrtYd")
		)
		(fp_rect
			(start -0.508 0.9398)
			(end 0.508 -0.9398)
			(stroke
				(width 0)
				(type default)
			)
			(fill no)
			(layer "F.Fab")
		)
		(pad "1" smd custom
			(at 0 -0.4445 270)
			(size 0.1397 0.1397)
			(layers "F.Cu" "F.Mask" "F.Paste")
			(net "SSD0_CLK0_OE_N")
			(options
				(clearance outline)
				(anchor circle)
			)
			(primitives
				(gr_poly
					(pts
						(arc
							(start -0.1778 -0.2794)
							(mid -0.249642 -0.249642)
							(end -0.2794 -0.1778)
						)
						(arc
							(start -0.2794 0.1778)
							(mid -0.249642 0.249642)
							(end -0.1778 0.2794)
						)
						(arc
							(start 0.1778 0.2794)
							(mid 0.249642 0.249642)
							(end 0.2794 0.1778)
						)
						(arc
							(start 0.2794 -0.1778)
							(mid 0.249642 -0.249642)
							(end 0.1778 -0.2794)
						)
					)
					(width 0)
					(fill yes)
				)
			)
		)
		(pad "2" smd custom
			(at 0 0.4445 270)
			(size 0.1397 0.1397)
			(layers "F.Cu" "F.Mask" "F.Paste")
			(net "SSD0_CLK0_OE_R_N")
			(options
				(clearance outline)
				(anchor circle)
			)
			(primitives
				(gr_poly
					(pts
						(arc
							(start -0.1778 -0.2794)
							(mid -0.249642 -0.249642)
							(end -0.2794 -0.1778)
						)
						(arc
							(start -0.2794 0.1778)
							(mid -0.249642 0.249642)
							(end -0.1778 0.2794)
						)
						(arc
							(start 0.1778 0.2794)
							(mid 0.249642 0.249642)
							(end 0.2794 0.1778)
						)
						(arc
							(start 0.2794 -0.1778)
							(mid 0.249642 -0.249642)
							(end 0.1778 -0.2794)
						)
					)
					(width 0)
					(fill yes)
				)
			)
		)
	)
	(footprint ""
		(layer "F.Cu")
		(at 23.71725 -402.53285 -90)
		(property "Reference" "Q57"
			(at 0 0 270)
			(layer "F.SilkS")
			(hide yes)
			(effects
				(font
					(size 1.27 1.27)
				)
			)
		)
		(property "Value" "2N7002A-7-GP"
			(at 0.127 -8.9662 270)
			(unlocked yes)
			(layer "F.Fab")
			(hide yes)
			(effects
				(font
					(size 1.016 1.016)
					(thickness 0.1524)
				)
			)
		)
		(property "Device Type" "SOT23DGS2D4H48"
			(at 0.127 -10.4902 270)
			(unlocked yes)
			(layer "F.Fab")
			(hide yes)
			(effects
				(font
					(size 1.016 1.016)
					(thickness 0.1524)
				)
			)
		)
		(duplicate_pad_numbers_are_jumpers no)
		(fp_line
			(start -1.651 1.778)
			(end 1.651 1.778)
			(stroke
				(width 0.1524)
				(type default)
			)
			(layer "F.SilkS")
		)
		(fp_line
			(start 1.651 1.778)
			(end 1.651 -1.778)
			(stroke
				(width 0.1524)
				(type default)
			)
			(layer "F.SilkS")
		)
		(fp_line
			(start -1.651 -1.778)
			(end -1.651 1.778)
			(stroke
				(width 0.1524)
				(type default)
			)
			(layer "F.SilkS")
		)
		(fp_line
			(start 1.651 -1.778)
			(end -1.651 -1.778)
			(stroke
				(width 0.1524)
				(type default)
			)
			(layer "F.SilkS")
		)
		(fp_poly
			(pts
				(xy -1.778 1.8796) (xy -1.778 -1.8796) (xy 1.778 -1.8796) (xy 1.778 1.8796)
			)
			(stroke
				(width 0)
				(type default)
			)
			(fill no)
			(layer "F.CrtYd")
		)
		(fp_poly
			(pts
				(xy -1.778 1.8796) (xy -1.778 -1.8796) (xy 1.778 -1.8796) (xy 1.778 1.8796)
			)
			(stroke
				(width 0)
				(type default)
			)
			(fill no)
			(layer "F.Fab")
		)
		(pad "D" smd custom
			(at 0 -0.9525 270)
			(size 0.1905 0.1905)
			(layers "F.Cu" "F.Mask" "F.Paste")
			(net "P12V_MOST6_GATE")
			(options
				(clearance outline)
				(anchor circle)
			)
			(primitives
				(gr_poly
					(pts
						(arc
							(start -0.1778 0.5715)
							(mid -0.321484 0.511984)
							(end -0.381 0.3683)
						)
						(arc
							(start -0.381 -0.3683)
							(mid -0.321484 -0.511984)
							(end -0.1778 -0.5715)
						)
						(arc
							(start 0.1778 -0.5715)
							(mid 0.321484 -0.511984)
							(end 0.381 -0.3683)
						)
						(arc
							(start 0.381 0.3683)
							(mid 0.321484 0.511984)
							(end 0.1778 0.5715)
						)
					)
					(width 0)
					(fill yes)
				)
			)
		)
		(pad "G" smd custom
			(at -0.98425 0.9525 270)
			(size 0.1905 0.1905)
			(layers "F.Cu" "F.Mask" "F.Paste")
			(net "SSD6_PWREN_R")
			(options
				(clearance outline)
				(anchor circle)
			)
			(primitives
				(gr_poly
					(pts
						(arc
							(start -0.1778 0.5715)
							(mid -0.321484 0.511984)
							(end -0.381 0.3683)
						)
						(arc
							(start -0.381 -0.3683)
							(mid -0.321484 -0.511984)
							(end -0.1778 -0.5715)
						)
						(arc
							(start 0.1778 -0.5715)
							(mid 0.321484 -0.511984)
							(end 0.381 -0.3683)
						)
						(arc
							(start 0.381 0.3683)
							(mid 0.321484 0.511984)
							(end 0.1778 0.5715)
						)
					)
					(width 0)
					(fill yes)
				)
			)
		)
		(pad "S" smd custom
			(at 0.98425 0.9525 270)
			(size 0.1905 0.1905)
			(layers "F.Cu" "F.Mask" "F.Paste")
			(net "GND")
			(options
				(clearance outline)
				(anchor circle)
			)
			(primitives
				(gr_poly
					(pts
						(arc
							(start -0.1778 0.5715)
							(mid -0.321484 0.511984)
							(end -0.381 0.3683)
						)
						(arc
							(start -0.381 -0.3683)
							(mid -0.321484 -0.511984)
							(end -0.1778 -0.5715)
						)
						(arc
							(start 0.1778 -0.5715)
							(mid 0.321484 -0.511984)
							(end 0.381 -0.3683)
						)
						(arc
							(start 0.381 0.3683)
							(mid 0.321484 0.511984)
							(end 0.1778 0.5715)
						)
					)
					(width 0)
					(fill yes)
				)
			)
		)
	)
	(footprint ""
		(layer "F.Cu")
		(at 38.6334 -13.6652 180)
		(property "Reference" "PC1231"
			(at 0 0 180)
			(layer "F.SilkS")
			(hide yes)
			(effects
				(font
					(size 1.27 1.27)
				)
			)
		)
		(property "Value" "SC22U25V6KX-GP-U"
			(at -2.860802 -5.279644 180)
			(unlocked yes)
			(layer "F.Fab")
			(hide yes)
			(effects
				(font
					(size 1.016 1.016)
					(thickness 0.1524)
				)
			)
		)
		(property "Device Type" "C1206-TO0D3H75"
			(at -2.860802 -6.803644 180)
			(unlocked yes)
			(layer "F.Fab")
			(hide yes)
			(effects
				(font
					(size 1.016 1.016)
					(thickness 0.1524)
				)
			)
		)
		(duplicate_pad_numbers_are_jumpers no)
		(fp_line
			(start 1.3081 2.3749)
			(end -1.3081 2.3749)
			(stroke
				(width 0.1524)
				(type default)
			)
			(layer "F.SilkS")
		)
		(fp_line
			(start 1.3081 -2.3749)
			(end 1.3081 2.3749)
			(stroke
				(width 0.1524)
				(type default)
			)
			(layer "F.SilkS")
		)
		(fp_line
			(start -1.3081 2.3749)
			(end -1.3081 -2.3749)
			(stroke
				(width 0.1524)
				(type default)
			)
			(layer "F.SilkS")
		)
		(fp_line
			(start -1.3081 -2.3749)
			(end 1.3081 -2.3749)
			(stroke
				(width 0.1524)
				(type default)
			)
			(layer "F.SilkS")
		)
		(fp_rect
			(start -0.8001 1.6002)
			(end 0.8001 -1.6002)
			(stroke
				(width 0)
				(type default)
			)
			(fill no)
			(layer "F.CrtYd")
		)
		(fp_poly
			(pts
				(xy -1.5621 2.4511) (xy -1.5621 1.6002) (xy 0.8001 1.6002) (xy 0.8001 -1.6002) (xy -0.8001 -1.6002)
				(xy -0.8001 1.5875) (xy -1.5621 1.5875) (xy -1.5621 -2.4511) (xy 1.5621 -2.4511) (xy 1.5621 2.4511)
			)
			(stroke
				(width 0)
				(type default)
			)
			(fill no)
			(layer "F.CrtYd")
		)
		(fp_rect
			(start -1.5621 2.4511)
			(end 1.5621 -2.4511)
			(stroke
				(width 0)
				(type default)
			)
			(fill no)
			(layer "F.Fab")
		)
		(pad "1" smd rect
			(at 0 -1.392936 180)
			(size 2.1082 1.4478)
			(layers "F.Cu" "F.Mask" "F.Paste")
			(net "P12V_SSD14")
		)
		(pad "2" smd rect
			(at 0 1.392936 180)
			(size 2.1082 1.4478)
			(layers "F.Cu" "F.Mask" "F.Paste")
			(net "GND")
		)
	)
	(footprint ""
		(layer "F.Cu")
		(at 215.9 -403.9616 -90)
		(property "Reference" "Q32"
			(at 0 0 270)
			(layer "F.SilkS")
			(hide yes)
			(effects
				(font
					(size 1.27 1.27)
				)
			)
		)
		(property "Value" "2N7002A-7-GP"
			(at 0.127 -8.9662 270)
			(unlocked yes)
			(layer "F.Fab")
			(hide yes)
			(effects
				(font
					(size 1.016 1.016)
					(thickness 0.1524)
				)
			)
		)
		(property "Device Type" "SOT23DGS2D4H48"
			(at 0.127 -10.4902 270)
			(unlocked yes)
			(layer "F.Fab")
			(hide yes)
			(effects
				(font
					(size 1.016 1.016)
					(thickness 0.1524)
				)
			)
		)
		(duplicate_pad_numbers_are_jumpers no)
		(fp_line
			(start -1.651 1.778)
			(end 1.651 1.778)
			(stroke
				(width 0.1524)
				(type default)
			)
			(layer "F.SilkS")
		)
		(fp_line
			(start 1.651 1.778)
			(end 1.651 -1.778)
			(stroke
				(width 0.1524)
				(type default)
			)
			(layer "F.SilkS")
		)
		(fp_line
			(start -1.651 -1.778)
			(end -1.651 1.778)
			(stroke
				(width 0.1524)
				(type default)
			)
			(layer "F.SilkS")
		)
		(fp_line
			(start 1.651 -1.778)
			(end -1.651 -1.778)
			(stroke
				(width 0.1524)
				(type default)
			)
			(layer "F.SilkS")
		)
		(fp_poly
			(pts
				(xy -1.778 1.8796) (xy -1.778 -1.8796) (xy 1.778 -1.8796) (xy 1.778 1.8796)
			)
			(stroke
				(width 0)
				(type default)
			)
			(fill no)
			(layer "F.CrtYd")
		)
		(fp_poly
			(pts
				(xy -1.778 1.8796) (xy -1.778 -1.8796) (xy 1.778 -1.8796) (xy 1.778 1.8796)
			)
			(stroke
				(width 0)
				(type default)
			)
			(fill no)
			(layer "F.Fab")
		)
		(pad "D" smd custom
			(at 0 -0.9525 270)
			(size 0.1905 0.1905)
			(layers "F.Cu" "F.Mask" "F.Paste")
			(net "P12V_MOST1_GATE_D")
			(options
				(clearance outline)
				(anchor circle)
			)
			(primitives
				(gr_poly
					(pts
						(arc
							(start -0.1778 0.5715)
							(mid -0.321484 0.511984)
							(end -0.381 0.3683)
						)
						(arc
							(start -0.381 -0.3683)
							(mid -0.321484 -0.511984)
							(end -0.1778 -0.5715)
						)
						(arc
							(start 0.1778 -0.5715)
							(mid 0.321484 -0.511984)
							(end 0.381 -0.3683)
						)
						(arc
							(start 0.381 0.3683)
							(mid 0.321484 0.511984)
							(end 0.1778 0.5715)
						)
					)
					(width 0)
					(fill yes)
				)
			)
		)
		(pad "G" smd custom
			(at -0.98425 0.9525 270)
			(size 0.1905 0.1905)
			(layers "F.Cu" "F.Mask" "F.Paste")
			(net "P12V_MOST1_GATE")
			(options
				(clearance outline)
				(anchor circle)
			)
			(primitives
				(gr_poly
					(pts
						(arc
							(start -0.1778 0.5715)
							(mid -0.321484 0.511984)
							(end -0.381 0.3683)
						)
						(arc
							(start -0.381 -0.3683)
							(mid -0.321484 -0.511984)
							(end -0.1778 -0.5715)
						)
						(arc
							(start 0.1778 -0.5715)
							(mid 0.321484 -0.511984)
							(end 0.381 -0.3683)
						)
						(arc
							(start 0.381 0.3683)
							(mid 0.321484 0.511984)
							(end 0.1778 0.5715)
						)
					)
					(width 0)
					(fill yes)
				)
			)
		)
		(pad "S" smd custom
			(at 0.98425 0.9525 270)
			(size 0.1905 0.1905)
			(layers "F.Cu" "F.Mask" "F.Paste")
			(net "GND")
			(options
				(clearance outline)
				(anchor circle)
			)
			(primitives
				(gr_poly
					(pts
						(arc
							(start -0.1778 0.5715)
							(mid -0.321484 0.511984)
							(end -0.381 0.3683)
						)
						(arc
							(start -0.381 -0.3683)
							(mid -0.321484 -0.511984)
							(end -0.1778 -0.5715)
						)
						(arc
							(start 0.1778 -0.5715)
							(mid 0.321484 -0.511984)
							(end 0.381 -0.3683)
						)
						(arc
							(start 0.381 0.3683)
							(mid 0.321484 0.511984)
							(end 0.1778 0.5715)
						)
					)
					(width 0)
					(fill yes)
				)
			)
		)
	)
	(footprint ""
		(layer "F.Cu")
		(at 16.637 -491.363 180)
		(property "Reference" "R571"
			(at 0 0 180)
			(layer "F.SilkS")
			(hide yes)
			(effects
				(font
					(size 1.27 1.27)
				)
			)
		)
		(property "Value" "300KR2F-GP"
			(at 0.064008 -3.993896 180)
			(unlocked yes)
			(layer "F.Fab")
			(hide yes)
			(effects
				(font
					(size 1.016 1.016)
					(thickness 0.1524)
				)
			)
		)
		(property "Device Type" "R402H16"
			(at 0.064008 -5.517896 180)
			(unlocked yes)
			(layer "F.Fab")
			(hide yes)
			(effects
				(font
					(size 1.016 1.016)
					(thickness 0.1524)
				)
			)
		)
		(duplicate_pad_numbers_are_jumpers no)
		(fp_line
			(start 0.508 -0.9398)
			(end -0.508 -0.9398)
			(stroke
				(width 0.1524)
				(type default)
			)
			(layer "F.SilkS")
		)
		(fp_line
			(start -0.508 -0.9398)
			(end -0.508 0.9398)
			(stroke
				(width 0.1524)
				(type default)
			)
			(layer "F.SilkS")
		)
		(fp_rect
			(start -0.508 0.9398)
			(end 0.508 -0.9398)
			(stroke
				(width 0)
				(type default)
			)
			(fill no)
			(layer "F.CrtYd")
		)
		(fp_rect
			(start -0.508 0.9398)
			(end 0.508 -0.9398)
			(stroke
				(width 0)
				(type default)
			)
			(fill no)
			(layer "F.Fab")
		)
		(pad "1" smd custom
			(at 0 -0.4445 180)
			(size 0.1397 0.1397)
			(layers "F.Cu" "F.Mask" "F.Paste")
			(net "SW_SSD5_N")
			(options
				(clearance outline)
				(anchor circle)
			)
			(primitives
				(gr_poly
					(pts
						(arc
							(start -0.1778 -0.2794)
							(mid -0.249642 -0.249642)
							(end -0.2794 -0.1778)
						)
						(arc
							(start -0.2794 0.1778)
							(mid -0.249642 0.249642)
							(end -0.1778 0.2794)
						)
						(arc
							(start 0.1778 0.2794)
							(mid 0.249642 0.249642)
							(end 0.2794 0.1778)
						)
						(arc
							(start 0.2794 -0.1778)
							(mid 0.249642 -0.249642)
							(end 0.1778 -0.2794)
						)
					)
					(width 0)
					(fill yes)
				)
			)
		)
		(pad "2" smd custom
			(at 0 0.4445 180)
			(size 0.1397 0.1397)
			(layers "F.Cu" "F.Mask" "F.Paste")
			(net "P12V")
			(options
				(clearance outline)
				(anchor circle)
			)
			(primitives
				(gr_poly
					(pts
						(arc
							(start -0.1778 -0.2794)
							(mid -0.249642 -0.249642)
							(end -0.2794 -0.1778)
						)
						(arc
							(start -0.2794 0.1778)
							(mid -0.249642 0.249642)
							(end -0.1778 0.2794)
						)
						(arc
							(start 0.1778 0.2794)
							(mid 0.249642 0.249642)
							(end 0.2794 0.1778)
						)
						(arc
							(start 0.2794 -0.1778)
							(mid 0.249642 -0.249642)
							(end 0.1778 -0.2794)
						)
					)
					(width 0)
					(fill yes)
				)
			)
		)
	)
)
